(kicad_pcb
	(version 20260206)
	(generator "pcbnew")
	(generator_version "10.0")
	(general
		(thickness 1.6)
		(legacy_teardrops no)
	)
	(paper "A4")
	(title_block
		(title "04192023_DAF0TMB3IC0_F0TG_MB_C_brd_V02_OCP.brd")
		(comment 1 "Grand Teton / footprint 3955 of 8354 (U25), pads 4558-4668 of 6102")
	)
	(layers
		(0 "F.Cu" signal "TOP")
		(4 "In1.Cu" signal "GND")
		(6 "In2.Cu" signal "IN1")
		(8 "In3.Cu" signal "GND1")
		(10 "In4.Cu" signal "IN2")
		(12 "In5.Cu" signal "GND2")
		(14 "In6.Cu" signal "IN3")
		(16 "In7.Cu" signal "GND3")
		(18 "In8.Cu" signal "VCC")
		(20 "In9.Cu" signal "VCC1")
		(22 "In10.Cu" signal "GND4")
		(24 "In11.Cu" signal "IN4")
		(26 "In12.Cu" signal "GND5")
		(28 "In13.Cu" signal "IN5")
		(30 "In14.Cu" signal "GND6")
		(32 "In15.Cu" signal "IN6")
		(34 "In16.Cu" signal "GND7")
		(2 "B.Cu" signal "BOTTOM")
		(9 "F.Adhes" user "F.Adhesive")
		(11 "B.Adhes" user "B.Adhesive")
		(13 "F.Paste" user "Package Geometry/Pastemask Top")
		(15 "B.Paste" user "Package Geometry/Pastemask Bottom")
		(5 "F.SilkS" user "Ref Des/Silkscreen Top")
		(7 "B.SilkS" user "Ref Des/Silkscreen Bottom")
		(1 "F.Mask" user "Board Geometry/Soldermask Top")
		(3 "B.Mask" user "Board Geometry/Soldermask Bottom")
		(17 "Dwgs.User" user "User.Drawings")
		(19 "Cmts.User" user "User.Comments")
		(21 "Eco1.User" user "User.Eco1")
		(23 "Eco2.User" user "User.Eco2")
		(25 "Edge.Cuts" user "Board Geometry/Outline")
		(27 "Margin" user)
		(31 "F.CrtYd" user "Package Geometry/Place Bound Top")
		(29 "B.CrtYd" user "Package Geometry/Place Bound Bottom")
		(35 "F.Fab" user "Ref Des/Assembly Top")
		(33 "B.Fab" user "Ref Des/Assembly Bottom")
	)
	(footprint ""
		(layer "F.Cu")
		(at 359.867962 -258.880102 180)
		(property "Reference" "U25"
			(at -45.78477 -62.086744 0)
			(unlocked yes)
			(layer "F.SilkS")
			(effects
				(font
					(size 0.7874 0.5842)
					(thickness 0.1524)
				)
			)
		)
		(property "Value" ""
			(at 0 0 180)
			(layer "F.Fab")
			(effects
				(font
					(size 1.27 1.27)
				)
			)
		)
		(duplicate_pad_numbers_are_jumpers no)
		(pad "DD23" smd circle
			(at -14.249908 32.759904 180)
			(size 0.450088 0.450088)
			(layers "F.Cu" "F.Mask" "F.Paste")
			(net "GND")
		)
		(pad "DD24" smd circle
			(at -13.310108 32.759904 180)
			(size 0.450088 0.450088)
			(layers "F.Cu" "F.Mask" "F.Paste")
			(net "GND")
		)
		(pad "DD25" smd circle
			(at -12.370054 32.759904 180)
			(size 0.450088 0.450088)
			(layers "F.Cu" "F.Mask" "F.Paste")
			(net "PVDDCR_CPU1_P0")
		)
		(pad "DD26" smd circle
			(at -11.43 32.759904 180)
			(size 0.450088 0.450088)
			(layers "F.Cu" "F.Mask" "F.Paste")
			(net "GND")
		)
		(pad "DD27" smd circle
			(at -10.489946 32.759904 180)
			(size 0.450088 0.450088)
			(layers "F.Cu" "F.Mask" "F.Paste")
			(net "GND")
		)
		(pad "DD28" smd circle
			(at -9.549892 32.759904 180)
			(size 0.450088 0.450088)
			(layers "F.Cu" "F.Mask" "F.Paste")
			(net "PVDDCR_CPU1_P0")
		)
		(pad "DD29" smd circle
			(at -8.610092 32.759904 180)
			(size 0.450088 0.450088)
			(layers "F.Cu" "F.Mask" "F.Paste")
			(net "GND")
		)
		(pad "DD30" smd circle
			(at -7.670038 32.759904 180)
			(size 0.450088 0.450088)
			(layers "F.Cu" "F.Mask" "F.Paste")
			(net "GND")
		)
		(pad "DD31" smd circle
			(at -6.729984 32.759904 180)
			(size 0.450088 0.450088)
			(layers "F.Cu" "F.Mask" "F.Paste")
			(net "PVDDCR_CPU1_P0")
		)
		(pad "DD32" smd circle
			(at -5.78993 32.759904 180)
			(size 0.450088 0.450088)
			(layers "F.Cu" "F.Mask" "F.Paste")
			(net "GND")
		)
		(pad "DD33" smd circle
			(at -4.849876 32.759904 180)
			(size 0.450088 0.450088)
			(layers "F.Cu" "F.Mask" "F.Paste")
			(net "GND")
		)
		(pad "DD34" smd circle
			(at -3.910076 32.759904 180)
			(size 0.450088 0.450088)
			(layers "F.Cu" "F.Mask" "F.Paste")
			(net "PVDDCR_CPU1_P0")
		)
		(pad "DD35" smd circle
			(at -2.970022 32.759904 180)
			(size 0.450088 0.450088)
			(layers "F.Cu" "F.Mask" "F.Paste")
			(net "GND")
		)
		(pad "DD36" smd circle
			(at -2.029968 32.759904 180)
			(size 0.450088 0.450088)
			(layers "F.Cu" "F.Mask" "F.Paste")
			(net "GND")
		)
		(pad "DD37" smd circle
			(at -1.089914 32.759904 180)
			(size 0.450088 0.450088)
			(layers "F.Cu" "F.Mask" "F.Paste")
			(net "GND")
		)
		(pad "DD39" smd circle
			(at 0.78994 32.759904 180)
			(size 0.450088 0.450088)
			(layers "F.Cu" "F.Mask" "F.Paste")
			(net "GND")
		)
		(pad "DD40" smd circle
			(at 1.729994 32.759904 180)
			(size 0.450088 0.450088)
			(layers "F.Cu" "F.Mask" "F.Paste")
			(net "GND")
		)
		(pad "DD41" smd circle
			(at 2.670048 32.759904 180)
			(size 0.450088 0.450088)
			(layers "F.Cu" "F.Mask" "F.Paste")
			(net "GND")
		)
		(pad "DD42" smd circle
			(at 3.610102 32.759904 180)
			(size 0.450088 0.450088)
			(layers "F.Cu" "F.Mask" "F.Paste")
			(net "PVDDCR_CPU1_P0")
		)
		(pad "DD43" smd circle
			(at 4.549902 32.759904 180)
			(size 0.450088 0.450088)
			(layers "F.Cu" "F.Mask" "F.Paste")
			(net "GND")
		)
		(pad "DD44" smd circle
			(at 5.489956 32.759904 180)
			(size 0.450088 0.450088)
			(layers "F.Cu" "F.Mask" "F.Paste")
			(net "GND")
		)
		(pad "DD45" smd circle
			(at 6.43001 32.759904 180)
			(size 0.450088 0.450088)
			(layers "F.Cu" "F.Mask" "F.Paste")
			(net "PVDDCR_CPU1_P0")
		)
		(pad "DD46" smd circle
			(at 7.370064 32.759904 180)
			(size 0.450088 0.450088)
			(layers "F.Cu" "F.Mask" "F.Paste")
			(net "GND")
		)
		(pad "DD47" smd circle
			(at 8.310118 32.759904 180)
			(size 0.450088 0.450088)
			(layers "F.Cu" "F.Mask" "F.Paste")
			(net "GND")
		)
		(pad "DD48" smd circle
			(at 9.249918 32.759904 180)
			(size 0.450088 0.450088)
			(layers "F.Cu" "F.Mask" "F.Paste")
			(net "PVDDCR_CPU1_P0")
		)
		(pad "DD49" smd circle
			(at 10.189972 32.759904 180)
			(size 0.450088 0.450088)
			(layers "F.Cu" "F.Mask" "F.Paste")
			(net "GND")
		)
		(pad "DD50" smd circle
			(at 11.130026 32.759904 180)
			(size 0.450088 0.450088)
			(layers "F.Cu" "F.Mask" "F.Paste")
			(net "GND")
		)
		(pad "DD51" smd circle
			(at 12.07008 32.759904 180)
			(size 0.450088 0.450088)
			(layers "F.Cu" "F.Mask" "F.Paste")
			(net "PVDDCR_CPU1_P0")
		)
		(pad "DD52" smd circle
			(at 13.00988 32.759904 180)
			(size 0.450088 0.450088)
			(layers "F.Cu" "F.Mask" "F.Paste")
			(net "GND")
		)
		(pad "DD53" smd circle
			(at 13.949934 32.759904 180)
			(size 0.450088 0.450088)
			(layers "F.Cu" "F.Mask" "F.Paste")
			(net "GND")
		)
		(pad "DD54" smd circle
			(at 14.889988 32.759904 180)
			(size 0.450088 0.450088)
			(layers "F.Cu" "F.Mask" "F.Paste")
			(net "PVDDCR_CPU1_P0")
		)
		(pad "DD55" smd circle
			(at 15.830042 32.759904 180)
			(size 0.450088 0.450088)
			(layers "F.Cu" "F.Mask" "F.Paste")
			(net "M_C_CPU0_SB_DQS_DP<8>")
		)
		(pad "DD56" smd circle
			(at 16.770096 32.759904 180)
			(size 0.450088 0.450088)
			(layers "F.Cu" "F.Mask" "F.Paste")
			(net "M_C_CPU0_SB_DQ<28>")
		)
		(pad "DD57" smd circle
			(at 17.709896 32.759904 180)
			(size 0.450088 0.450088)
			(layers "F.Cu" "F.Mask" "F.Paste")
			(net "GND")
		)
		(pad "DD58" smd circle
			(at 18.64995 32.759904 180)
			(size 0.450088 0.450088)
			(layers "F.Cu" "F.Mask" "F.Paste")
			(net "M_D_CPU0_SB_DQS_DP<8>")
		)
		(pad "DD59" smd circle
			(at 19.590004 32.759904 180)
			(size 0.450088 0.450088)
			(layers "F.Cu" "F.Mask" "F.Paste")
			(net "GND")
		)
		(pad "DD60" smd circle
			(at 20.530058 32.759904 180)
			(size 0.450088 0.450088)
			(layers "F.Cu" "F.Mask" "F.Paste")
			(net "M_D_CPU0_SB_DQ<28>")
		)
		(pad "DD61" smd circle
			(at 21.470112 32.759904 180)
			(size 0.450088 0.450088)
			(layers "F.Cu" "F.Mask" "F.Paste")
			(net "GND")
		)
		(pad "DD62" smd circle
			(at 22.409912 32.759904 180)
			(size 0.450088 0.450088)
			(layers "F.Cu" "F.Mask" "F.Paste")
			(net "M_B_CPU0_SB_DQS_DP<8>")
		)
		(pad "DD63" smd circle
			(at 23.349966 32.759904 180)
			(size 0.450088 0.450088)
			(layers "F.Cu" "F.Mask" "F.Paste")
			(net "M_B_CPU0_SB_DQ<28>")
		)
		(pad "DD64" smd circle
			(at 24.29002 32.759904 180)
			(size 0.450088 0.450088)
			(layers "F.Cu" "F.Mask" "F.Paste")
			(net "GND")
		)
		(pad "DD65" smd circle
			(at 25.230074 32.759904 180)
			(size 0.450088 0.450088)
			(layers "F.Cu" "F.Mask" "F.Paste")
			(net "M_F_CPU0_SB_DQS_DP<8>")
		)
		(pad "DD66" smd circle
			(at 26.170128 32.759904 180)
			(size 0.450088 0.450088)
			(layers "F.Cu" "F.Mask" "F.Paste")
			(net "GND")
		)
		(pad "DD67" smd circle
			(at 27.109928 32.759904 180)
			(size 0.450088 0.450088)
			(layers "F.Cu" "F.Mask" "F.Paste")
			(net "M_F_CPU0_SB_DQ<28>")
		)
		(pad "DD68" smd circle
			(at 28.049982 32.759904 180)
			(size 0.450088 0.450088)
			(layers "F.Cu" "F.Mask" "F.Paste")
			(net "GND")
		)
		(pad "DD69" smd circle
			(at 28.990036 32.759904 180)
			(size 0.450088 0.450088)
			(layers "F.Cu" "F.Mask" "F.Paste")
			(net "M_E_CPU0_SB_DQS_DP<8>")
		)
		(pad "DD70" smd circle
			(at 29.93009 32.759904 180)
			(size 0.450088 0.450088)
			(layers "F.Cu" "F.Mask" "F.Paste")
			(net "M_E_CPU0_SB_DQ<28>")
		)
		(pad "DD71" smd circle
			(at 30.86989 32.759904 180)
			(size 0.450088 0.450088)
			(layers "F.Cu" "F.Mask" "F.Paste")
			(net "GND")
		)
		(pad "DD72" smd circle
			(at 31.809944 32.759904 180)
			(size 0.450088 0.450088)
			(layers "F.Cu" "F.Mask" "F.Paste")
			(net "M_A_CPU0_SB_DQS_DP<8>")
		)
		(pad "DD73" smd circle
			(at 32.749998 32.759904 180)
			(size 0.450088 0.450088)
			(layers "F.Cu" "F.Mask" "F.Paste")
			(net "GND")
		)
		(pad "DD74" smd circle
			(at 33.690052 32.759904 180)
			(size 0.450088 0.450088)
			(layers "F.Cu" "F.Mask" "F.Paste")
			(net "M_A_CPU0_SB_DQ<28>")
		)
		(pad "DE1" smd circle
			(at -34.459926 33.56991 180)
			(size 0.450088 0.450088)
			(layers "F.Cu" "F.Mask" "F.Paste")
			(net "GND")
		)
		(pad "DE2" smd circle
			(at -33.519872 33.56991 180)
			(size 0.450088 0.450088)
			(layers "F.Cu" "F.Mask" "F.Paste")
			(net "M_G_CPU0_SB_DQ<30>")
		)
		(pad "DE3" smd circle
			(at -32.580072 33.56991 180)
			(size 0.450088 0.450088)
			(layers "F.Cu" "F.Mask" "F.Paste")
			(net "M_G_CPU0_SB_DQ<29>")
		)
		(pad "DE4" smd circle
			(at -31.640018 33.56991 180)
			(size 0.450088 0.450088)
			(layers "F.Cu" "F.Mask" "F.Paste")
			(net "PVDD11_S3_P0")
		)
		(pad "DE5" smd circle
			(at -30.699964 33.56991 180)
			(size 0.450088 0.450088)
			(layers "F.Cu" "F.Mask" "F.Paste")
			(net "M_K_CPU0_SB_DQ<30>")
		)
		(pad "DE6" smd circle
			(at -29.75991 33.56991 180)
			(size 0.450088 0.450088)
			(layers "F.Cu" "F.Mask" "F.Paste")
			(net "GND")
		)
		(pad "DE7" smd circle
			(at -28.82011 33.56991 180)
			(size 0.450088 0.450088)
			(layers "F.Cu" "F.Mask" "F.Paste")
			(net "M_K_CPU0_SB_DQ<29>")
		)
		(pad "DE8" smd circle
			(at -27.880056 33.56991 180)
			(size 0.450088 0.450088)
			(layers "F.Cu" "F.Mask" "F.Paste")
			(net "GND")
		)
		(pad "DE9" smd circle
			(at -26.940002 33.56991 180)
			(size 0.450088 0.450088)
			(layers "F.Cu" "F.Mask" "F.Paste")
			(net "M_L_CPU0_SB_DQ<30>")
		)
		(pad "DE10" smd circle
			(at -25.999948 33.56991 180)
			(size 0.450088 0.450088)
			(layers "F.Cu" "F.Mask" "F.Paste")
			(net "M_L_CPU0_SB_DQ<29>")
		)
		(pad "DE11" smd circle
			(at -25.059894 33.56991 180)
			(size 0.450088 0.450088)
			(layers "F.Cu" "F.Mask" "F.Paste")
			(net "PVDD11_S3_P0")
		)
		(pad "DE12" smd circle
			(at -24.120094 33.56991 180)
			(size 0.450088 0.450088)
			(layers "F.Cu" "F.Mask" "F.Paste")
			(net "M_H_CPU0_SB_DQ<30>")
		)
		(pad "DE13" smd circle
			(at -23.18004 33.56991 180)
			(size 0.450088 0.450088)
			(layers "F.Cu" "F.Mask" "F.Paste")
			(net "GND")
		)
		(pad "DE14" smd circle
			(at -22.239986 33.56991 180)
			(size 0.450088 0.450088)
			(layers "F.Cu" "F.Mask" "F.Paste")
			(net "M_H_CPU0_SB_DQ<29>")
		)
		(pad "DE15" smd circle
			(at -21.299932 33.56991 180)
			(size 0.450088 0.450088)
			(layers "F.Cu" "F.Mask" "F.Paste")
			(net "GND")
		)
		(pad "DE16" smd circle
			(at -20.359878 33.56991 180)
			(size 0.450088 0.450088)
			(layers "F.Cu" "F.Mask" "F.Paste")
			(net "M_J_CPU0_SB_DQ<30>")
		)
		(pad "DE17" smd circle
			(at -19.420078 33.56991 180)
			(size 0.450088 0.450088)
			(layers "F.Cu" "F.Mask" "F.Paste")
			(net "M_J_CPU0_SB_DQ<29>")
		)
		(pad "DE18" smd circle
			(at -18.480024 33.56991 180)
			(size 0.450088 0.450088)
			(layers "F.Cu" "F.Mask" "F.Paste")
			(net "PVDD11_S3_P0")
		)
		(pad "DE19" smd circle
			(at -17.53997 33.56991 180)
			(size 0.450088 0.450088)
			(layers "F.Cu" "F.Mask" "F.Paste")
			(net "M_I_CPU0_SB_DQ<30>")
		)
		(pad "DE20" smd circle
			(at -16.599916 33.56991 180)
			(size 0.450088 0.450088)
			(layers "F.Cu" "F.Mask" "F.Paste")
			(net "GND")
		)
		(pad "DE21" smd circle
			(at -15.660116 33.56991 180)
			(size 0.450088 0.450088)
			(layers "F.Cu" "F.Mask" "F.Paste")
			(net "M_I_CPU0_SB_DQ<29>")
		)
		(pad "DE22" smd circle
			(at -14.720062 33.56991 180)
			(size 0.450088 0.450088)
			(layers "F.Cu" "F.Mask" "F.Paste")
			(net "PVDDCR_CPU1_P0")
		)
		(pad "DE23" smd circle
			(at -13.780008 33.56991 180)
			(size 0.450088 0.450088)
			(layers "F.Cu" "F.Mask" "F.Paste")
			(net "GND")
		)
		(pad "DE24" smd circle
			(at -12.839954 33.56991 180)
			(size 0.450088 0.450088)
			(layers "F.Cu" "F.Mask" "F.Paste")
			(net "ESPI_CPU0_R_D1")
		)
		(pad "DE25" smd circle
			(at -11.8999 33.56991 180)
			(size 0.450088 0.450088)
			(layers "F.Cu" "F.Mask" "F.Paste")
			(net "PVDDCR_CPU1_P0")
		)
		(pad "DE26" smd circle
			(at -10.9601 33.56991 180)
			(size 0.450088 0.450088)
			(layers "F.Cu" "F.Mask" "F.Paste")
			(net "GND")
		)
		(pad "DE27" smd circle
			(at -10.020046 33.56991 180)
			(size 0.450088 0.450088)
			(layers "F.Cu" "F.Mask" "F.Paste")
			(net "RST_ESPI_CPU0_R_RSTOUT_N")
		)
		(pad "DE28" smd circle
			(at -9.079992 33.56991 180)
			(size 0.450088 0.450088)
			(layers "F.Cu" "F.Mask" "F.Paste")
			(net "PVDDCR_CPU1_P0")
		)
		(pad "DE29" smd circle
			(at -8.139938 33.56991 180)
			(size 0.450088 0.450088)
			(layers "F.Cu" "F.Mask" "F.Paste")
			(net "GND")
		)
		(pad "DE30" smd circle
			(at -7.199884 33.56991 180)
			(size 0.450088 0.450088)
			(layers "F.Cu" "F.Mask" "F.Paste")
			(net "BIOS_DEBUG_MODE")
		)
		(pad "DE31" smd circle
			(at -6.260084 33.56991 180)
			(size 0.450088 0.450088)
			(layers "F.Cu" "F.Mask" "F.Paste")
			(net "PVDDCR_CPU1_P0")
		)
		(pad "DE32" smd circle
			(at -5.32003 33.56991 180)
			(size 0.450088 0.450088)
			(layers "F.Cu" "F.Mask" "F.Paste")
			(net "FM_BOARD_SKU_ID1")
		)
		(pad "DE33" smd circle
			(at -4.379976 33.56991 180)
			(size 0.450088 0.450088)
			(layers "F.Cu" "F.Mask" "F.Paste")
			(net "GND")
		)
		(pad "DE34" smd circle
			(at -3.439922 33.56991 180)
			(size 0.450088 0.450088)
			(layers "F.Cu" "F.Mask" "F.Paste")
			(net "PVDDCR_CPU1_P0")
		)
		(pad "DE35" smd circle
			(at -2.500122 33.56991 180)
			(size 0.450088 0.450088)
			(layers "F.Cu" "F.Mask" "F.Paste")
			(net "PVDDCR_CPU1_P0")
		)
		(pad "DE36" smd circle
			(at -1.560068 33.56991 180)
			(size 0.450088 0.450088)
			(layers "F.Cu" "F.Mask" "F.Paste")
			(net "CPU0_SPD_HOST_CTRL_N")
		)
		(pad "DE40" smd circle
			(at 1.260094 33.56991 180)
			(size 0.450088 0.450088)
			(layers "F.Cu" "F.Mask" "F.Paste")
			(net "IRQ_BMC_SMI_N")
		)
		(pad "DE41" smd circle
			(at 2.199894 33.56991 180)
			(size 0.450088 0.450088)
			(layers "F.Cu" "F.Mask" "F.Paste")
			(net "PVDDCR_CPU1_P0")
		)
		(pad "DE42" smd circle
			(at 3.139948 33.56991 180)
			(size 0.450088 0.450088)
			(layers "F.Cu" "F.Mask" "F.Paste")
			(net "PVDDCR_CPU1_P0")
		)
		(pad "DE43" smd circle
			(at 4.080002 33.56991 180)
			(size 0.450088 0.450088)
			(layers "F.Cu" "F.Mask" "F.Paste")
			(net "P3E_CPU0_P4_TX_DN<3>")
		)
		(pad "DE44" smd circle
			(at 5.020056 33.56991 180)
			(size 0.450088 0.450088)
			(layers "F.Cu" "F.Mask" "F.Paste")
			(net "P3E_CPU0_P4_TX_DP<3>")
		)
		(pad "DE45" smd circle
			(at 5.96011 33.56991 180)
			(size 0.450088 0.450088)
			(layers "F.Cu" "F.Mask" "F.Paste")
			(net "PVDDCR_CPU1_P0")
		)
		(pad "DE46" smd circle
			(at 6.89991 33.56991 180)
			(size 0.450088 0.450088)
			(layers "F.Cu" "F.Mask" "F.Paste")
			(net "P3E_CPU0_P4_TX_DN<2>")
		)
		(pad "DE47" smd circle
			(at 7.839964 33.56991 180)
			(size 0.450088 0.450088)
			(layers "F.Cu" "F.Mask" "F.Paste")
			(net "P3E_CPU0_P4_TX_DP<2>")
		)
		(pad "DE48" smd circle
			(at 8.780018 33.56991 180)
			(size 0.450088 0.450088)
			(layers "F.Cu" "F.Mask" "F.Paste")
			(net "PVDDCR_CPU1_P0")
		)
		(pad "DE49" smd circle
			(at 9.720072 33.56991 180)
			(size 0.450088 0.450088)
			(layers "F.Cu" "F.Mask" "F.Paste")
			(net "P3E_CPU0_P4_TX_DN<1>")
		)
		(pad "DE50" smd circle
			(at 10.659872 33.56991 180)
			(size 0.450088 0.450088)
			(layers "F.Cu" "F.Mask" "F.Paste")
			(net "P3E_CPU0_P4_TX_DP<1>")
		)
		(pad "DE51" smd circle
			(at 11.599926 33.56991 180)
			(size 0.450088 0.450088)
			(layers "F.Cu" "F.Mask" "F.Paste")
			(net "PVDDCR_CPU1_P0")
		)
		(pad "DE52" smd circle
			(at 12.53998 33.56991 180)
			(size 0.450088 0.450088)
			(layers "F.Cu" "F.Mask" "F.Paste")
			(net "P3E_CPU0_P4_TX_DN<0>")
		)
		(pad "DE53" smd circle
			(at 13.480034 33.56991 180)
			(size 0.450088 0.450088)
			(layers "F.Cu" "F.Mask" "F.Paste")
			(net "P3E_CPU0_P4_TX_DP<0>")
		)
		(pad "DE54" smd circle
			(at 14.420088 33.56991 180)
			(size 0.450088 0.450088)
			(layers "F.Cu" "F.Mask" "F.Paste")
			(net "PVDDCR_CPU1_P0")
		)
		(pad "DE55" smd circle
			(at 15.359888 33.56991 180)
			(size 0.450088 0.450088)
			(layers "F.Cu" "F.Mask" "F.Paste")
			(net "M_C_CPU0_SB_DQ<29>")
		)
		(pad "DE56" smd circle
			(at 16.299942 33.56991 180)
			(size 0.450088 0.450088)
			(layers "F.Cu" "F.Mask" "F.Paste")
			(net "GND")
		)
		(pad "DE57" smd circle
			(at 17.239996 33.56991 180)
			(size 0.450088 0.450088)
			(layers "F.Cu" "F.Mask" "F.Paste")
			(net "M_C_CPU0_SB_DQ<30>")
		)
		(pad "DE58" smd circle
			(at 18.18005 33.56991 180)
			(size 0.450088 0.450088)
			(layers "F.Cu" "F.Mask" "F.Paste")
			(net "PVDDIO_P0")
		)
		(pad "DE59" smd circle
			(at 19.120104 33.56991 180)
			(size 0.450088 0.450088)
			(layers "F.Cu" "F.Mask" "F.Paste")
			(net "M_D_CPU0_SB_DQ<29>")
		)
		(pad "DE60" smd circle
			(at 20.059904 33.56991 180)
			(size 0.450088 0.450088)
			(layers "F.Cu" "F.Mask" "F.Paste")
			(net "M_D_CPU0_SB_DQ<30>")
		)
		(pad "DE61" smd circle
			(at 20.999958 33.56991 180)
			(size 0.450088 0.450088)
			(layers "F.Cu" "F.Mask" "F.Paste")
			(net "GND")
		)
		(pad "DE62" smd circle
			(at 21.940012 33.56991 180)
			(size 0.450088 0.450088)
			(layers "F.Cu" "F.Mask" "F.Paste")
			(net "M_B_CPU0_SB_DQ<29>")
		)
		(pad "DE63" smd circle
			(at 22.880066 33.56991 180)
			(size 0.450088 0.450088)
			(layers "F.Cu" "F.Mask" "F.Paste")
			(net "GND")
		)
	)
)
